(kicad_pcb
	(version 20260206)
	(generator "pcbnew")
	(generator_version "10.0")
	(general
		(thickness 1.6)
		(legacy_teardrops no)
	)
	(paper "A4")
	(title_block
		(title "Bryce Canyon_R.DPB_16317-1_OCP.brd")
		(comment 1 "Bryce Canyon / footprints 1156-1158 of 2099")
	)
	(layers
		(0 "F.Cu" signal "TOP")
		(4 "In1.Cu" signal "L2GND")
		(6 "In2.Cu" signal "L3")
		(8 "In3.Cu" signal "L4VCC")
		(10 "In4.Cu" signal "L5VCC")
		(12 "In5.Cu" signal "L6")
		(14 "In6.Cu" signal "L7GND")
		(2 "B.Cu" signal "BOTTOM")
		(9 "F.Adhes" user "F.Adhesive")
		(11 "B.Adhes" user "B.Adhesive")
		(13 "F.Paste" user "Package Geometry/Pastemask Top")
		(15 "B.Paste" user "Package Geometry/Pastemask Bottom")
		(5 "F.SilkS" user "Ref Des/Silkscreen Top")
		(7 "B.SilkS" user "Ref Des/Silkscreen Bottom")
		(1 "F.Mask" user "Board Geometry/Soldermask Top")
		(3 "B.Mask" user "Board Geometry/Soldermask Bottom")
		(17 "Dwgs.User" user "User.Drawings")
		(19 "Cmts.User" user "User.Comments")
		(21 "Eco1.User" user "User.Eco1")
		(23 "Eco2.User" user "User.Eco2")
		(25 "Edge.Cuts" user "Board Geometry/Outline")
		(27 "Margin" user)
		(31 "F.CrtYd" user "Package Geometry/Place Bound Top")
		(29 "B.CrtYd" user "Package Geometry/Place Bound Bottom")
		(35 "F.Fab" user "Ref Des/Assembly Top")
		(33 "B.Fab" user "Ref Des/Assembly Bottom")
	)
	(footprint ""
		(layer "F.Cu")
		(at 28.200096 -143.91005 -90)
		(property "Reference" "HDDSAS12"
			(at 0 0 270)
			(layer "F.SilkS")
			(hide yes)
			(effects
				(font
					(size 1.27 1.27)
				)
			)
		)
		(property "Value" "SKT-SAS15P-14P-45-GP"
			(at -20.7645 -8.9789 270)
			(unlocked yes)
			(layer "F.Fab")
			(hide yes)
			(effects
				(font
					(size 1.016 1.016)
					(thickness 0.1524)
				)
			)
		)
		(property "Device Type" "10120818-001C-TRLF"
			(at -20.7645 -10.5029 270)
			(unlocked yes)
			(layer "F.Fab")
			(hide yes)
			(effects
				(font
					(size 1.016 1.016)
					(thickness 0.1524)
				)
			)
		)
		(duplicate_pad_numbers_are_jumpers no)
		(fp_line
			(start 1.651 4.2926)
			(end 1.651 3.0099)
			(stroke
				(width 0.1524)
				(type default)
			)
			(layer "F.SilkS")
		)
		(fp_line
			(start 8.509 4.2926)
			(end 1.651 4.2926)
			(stroke
				(width 0.1524)
				(type default)
			)
			(layer "F.SilkS")
		)
		(fp_line
			(start -23.4188 3.0099)
			(end -23.4188 -3.2512)
			(stroke
				(width 0.1524)
				(type default)
			)
			(layer "F.SilkS")
		)
		(fp_line
			(start 1.651 3.0099)
			(end -23.4188 3.0099)
			(stroke
				(width 0.1524)
				(type default)
			)
			(layer "F.SilkS")
		)
		(fp_line
			(start 8.509 3.0099)
			(end 8.509 4.2926)
			(stroke
				(width 0.1524)
				(type default)
			)
			(layer "F.SilkS")
		)
		(fp_line
			(start 23.4188 3.0099)
			(end 8.509 3.0099)
			(stroke
				(width 0.1524)
				(type default)
			)
			(layer "F.SilkS")
		)
		(fp_line
			(start -23.4188 -3.2512)
			(end 23.4188 -3.2512)
			(stroke
				(width 0.1524)
				(type default)
			)
			(layer "F.SilkS")
		)
		(fp_line
			(start 23.4188 -3.2512)
			(end 23.4188 3.0099)
			(stroke
				(width 0.1524)
				(type default)
			)
			(layer "F.SilkS")
		)
		(fp_line
			(start 15.5067 -3.3401)
			(end 16.2687 -3.3401)
			(stroke
				(width 0.3302)
				(type default)
			)
			(layer "F.SilkS")
		)
		(fp_poly
			(pts
				(xy 15.868904 -3.230372) (xy 16.503904 -3.865372) (xy 15.233904 -3.865372)
			)
			(stroke
				(width 0)
				(type default)
			)
			(fill yes)
			(layer "F.SilkS")
		)
		(fp_poly
			(pts
				(xy -22.8727 -2.7559) (xy 22.8727 -2.7559) (xy 22.8727 2.7559) (xy 8.255 2.7559) (xy 8.255 3.5179)
				(xy 1.905 3.5179) (xy 1.905 2.7559) (xy -22.8727 2.7559)
			)
			(stroke
				(width 0)
				(type default)
			)
			(fill no)
			(layer "F.CrtYd")
		)
		(fp_poly
			(pts
				(xy 1.397 4.5466) (xy 1.397 3.2639) (xy -23.6728 3.2639) (xy -23.6728 -3.5052) (xy 23.6728 -3.5052)
				(xy 23.6728 -0.00635) (xy 22.8727 -0.00635) (xy 22.8727 -2.7559) (xy -22.8727 -2.7559) (xy -22.8727 2.7559)
				(xy 1.905 2.7559) (xy 1.905 3.5179) (xy 8.255 3.5179) (xy 8.255 2.7559) (xy 22.8727 2.7559) (xy 22.8727 0.00635)
				(xy 23.6728 0.00635) (xy 23.6728 3.2639) (xy 8.763 3.2639) (xy 8.763 4.5466)
			)
			(stroke
				(width 0)
				(type default)
			)
			(fill no)
			(layer "F.CrtYd")
		)
		(fp_poly
			(pts
				(xy 1.397 4.5466) (xy 1.397 3.2639) (xy -23.6728 3.2639) (xy -23.6728 -3.5052) (xy 23.6728 -3.5052)
				(xy 23.6728 3.2639) (xy 8.763 3.2639) (xy 8.763 4.5466)
			)
			(stroke
				(width 0)
				(type default)
			)
			(fill no)
			(layer "F.Fab")
		)
		(pad "" np_thru_hole circle
			(at -18.874994 0 270)
			(size 0.254 0.254)
			(drill 1.3462)
			(layers "*.Cu" "*.Mask")
			(clearance 0.9017)
			(thermal_gap 0.9017)
		)
		(pad "" np_thru_hole circle
			(at 18.874994 0 270)
			(size 0.254 0.254)
			(drill 0.9398)
			(layers "*.Cu" "*.Mask")
			(clearance 0.6985)
			(thermal_gap 0.6985)
		)
		(pad "G1" smd rect
			(at 21.874988 0 270)
			(size 2.5908 2.5908)
			(layers "F.Cu" "F.Mask" "F.Paste")
			(net "GND")
		)
		(pad "G2" smd rect
			(at -21.874988 0 270)
			(size 2.5908 2.5908)
			(layers "F.Cu" "F.Mask" "F.Paste")
			(net "GND")
		)
		(pad "P1" smd rect
			(at 1.905 -1.82499 270)
			(size 0.6096 2.3622)
			(layers "F.Cu" "F.Mask" "F.Paste")
			(net "Net_1744")
		)
		(pad "P2" smd rect
			(at 0.635 -1.82499 270)
			(size 0.6096 2.3622)
			(layers "F.Cu" "F.Mask" "F.Paste")
			(net "Net_1745")
		)
		(pad "P3" smd rect
			(at -0.635 -1.82499 270)
			(size 0.6096 2.3622)
			(layers "F.Cu" "F.Mask" "F.Paste")
			(net "Net_1746")
		)
		(pad "P4" smd rect
			(at -1.905 -1.82499 270)
			(size 0.6096 2.3622)
			(layers "F.Cu" "F.Mask" "F.Paste")
			(net "GND")
		)
		(pad "P5" smd rect
			(at -3.175 -1.82499 270)
			(size 0.6096 2.3622)
			(layers "F.Cu" "F.Mask" "F.Paste")
			(net "HDD_PRSNT_12")
		)
		(pad "P6" smd rect
			(at -4.445 -1.82499 270)
			(size 0.6096 2.3622)
			(layers "F.Cu" "F.Mask" "F.Paste")
			(net "GND")
		)
		(pad "P7" smd rect
			(at -5.715 -1.82499 270)
			(size 0.6096 2.3622)
			(layers "F.Cu" "F.Mask" "F.Paste")
			(net "5V_PRE_12")
		)
		(pad "P8" smd rect
			(at -6.985 -1.82499 270)
			(size 0.6096 2.3622)
			(layers "F.Cu" "F.Mask" "F.Paste")
			(net "P5V_HDD12")
		)
		(pad "P9" smd rect
			(at -8.255 -1.82499 270)
			(size 0.6096 2.3622)
			(layers "F.Cu" "F.Mask" "F.Paste")
			(net "P5V_HDD12")
		)
		(pad "P10" smd rect
			(at -9.525 -1.82499 270)
			(size 0.6096 2.3622)
			(layers "F.Cu" "F.Mask" "F.Paste")
			(net "GND")
		)
		(pad "P11" smd rect
			(at -10.795 -1.82499 270)
			(size 0.6096 2.3622)
			(layers "F.Cu" "F.Mask" "F.Paste")
			(net "ACT_HDD_12")
		)
		(pad "P12" smd rect
			(at -12.065 -1.82499 270)
			(size 0.6096 2.3622)
			(layers "F.Cu" "F.Mask" "F.Paste")
			(net "GND")
		)
		(pad "P13" smd rect
			(at -13.335 -1.82499 270)
			(size 0.6096 2.3622)
			(layers "F.Cu" "F.Mask" "F.Paste")
			(net "12V_PRE_12")
		)
		(pad "P14" smd rect
			(at -14.605 -1.82499 270)
			(size 0.6096 2.3622)
			(layers "F.Cu" "F.Mask" "F.Paste")
			(net "P12V_HDD12")
		)
		(pad "P15" smd rect
			(at -15.875 -1.82499 270)
			(size 0.6096 2.3622)
			(layers "F.Cu" "F.Mask" "F.Paste")
			(net "P12V_HDD12")
		)
		(pad "S1" smd rect
			(at 15.875 -1.82499 270)
			(size 0.6096 2.3622)
			(layers "F.Cu" "F.Mask" "F.Paste")
			(net "GND")
		)
		(pad "S2" smd rect
			(at 14.605 -1.82499 270)
			(size 0.6096 2.3622)
			(layers "F.Cu" "F.Mask" "F.Paste")
			(net "SAS_HDD_RX_P12")
		)
		(pad "S3" smd rect
			(at 13.335 -1.82499 270)
			(size 0.6096 2.3622)
			(layers "F.Cu" "F.Mask" "F.Paste")
			(net "SAS_HDD_RX_N12")
		)
		(pad "S4" smd rect
			(at 12.065 -1.82499 270)
			(size 0.6096 2.3622)
			(layers "F.Cu" "F.Mask" "F.Paste")
			(net "GND")
		)
		(pad "S5" smd rect
			(at 10.795 -1.82499 270)
			(size 0.6096 2.3622)
			(layers "F.Cu" "F.Mask" "F.Paste")
			(net "PHY_DRV_B_TO_SCC_B_12_DN")
		)
		(pad "S6" smd rect
			(at 9.525 -1.82499 270)
			(size 0.6096 2.3622)
			(layers "F.Cu" "F.Mask" "F.Paste")
			(net "PHY_DRV_B_TO_SCC_B_12_DP")
		)
		(pad "S7" smd rect
			(at 8.255 -1.82499 270)
			(size 0.6096 2.3622)
			(layers "F.Cu" "F.Mask" "F.Paste")
			(net "GND")
		)
		(pad "S8" smd rect
			(at 7.480046 2.845054 270)
			(size 0.508 2.3622)
			(layers "F.Cu" "F.Mask" "F.Paste")
			(net "GND")
		)
		(pad "S9" smd rect
			(at 6.679946 2.845054 270)
			(size 0.508 2.3622)
			(layers "F.Cu" "F.Mask" "F.Paste")
			(net "Net_435")
		)
		(pad "S10" smd rect
			(at 5.8801 2.845054 270)
			(size 0.508 2.3622)
			(layers "F.Cu" "F.Mask" "F.Paste")
			(net "Net_327")
		)
		(pad "S11" smd rect
			(at 5.08 2.845054 270)
			(size 0.508 2.3622)
			(layers "F.Cu" "F.Mask" "F.Paste")
			(net "GND")
		)
		(pad "S12" smd rect
			(at 4.2799 2.845054 270)
			(size 0.508 2.3622)
			(layers "F.Cu" "F.Mask" "F.Paste")
			(net "Net_363")
		)
		(pad "S13" smd rect
			(at 3.480054 2.845054 270)
			(size 0.508 2.3622)
			(layers "F.Cu" "F.Mask" "F.Paste")
			(net "Net_399")
		)
		(pad "S14" smd rect
			(at 2.679954 2.845054 270)
			(size 0.508 2.3622)
			(layers "F.Cu" "F.Mask" "F.Paste")
			(net "GND")
		)
		(zone
			(layer "F.Cu")
			(hatch none 0.5)
			(connect_pads
				(clearance 0)
			)
			(min_thickness 0.25)
			(keepout
				(tracks not_allowed)
				(vias allowed)
				(pads allowed)
				(copperpour not_allowed)
				(footprints allowed)
			)
			(placement
				(enabled no)
				(sheetname "")
			)
			(fill
				(thermal_gap 0.5)
				(thermal_bridge_width 0.5)
				(island_removal_mode 0)
			)
			(polygon
				(pts
					(xy 31.857696 -160.64865) (xy 24.783796 -160.64865) (xy 24.783796 -167.58285) (xy 25.888696 -167.58285)
					(xy 25.888696 -163.46805) (xy 30.511496 -163.46805) (xy 30.511496 -167.58285) (xy 31.857696 -167.58285)
				)
			)
		)
		(zone
			(layer "F.Cu")
			(hatch none 0.5)
			(connect_pads
				(clearance 0)
			)
			(min_thickness 0.25)
			(keepout
				(tracks allowed)
				(vias not_allowed)
				(pads allowed)
				(copperpour not_allowed)
				(footprints allowed)
			)
			(placement
				(enabled no)
				(sheetname "")
			)
			(fill
				(thermal_gap 0.5)
				(thermal_bridge_width 0.5)
				(island_removal_mode 0)
			)
			(polygon
				(pts
					(xy 31.857696 -160.64865) (xy 24.783796 -160.64865) (xy 24.783796 -167.58285) (xy 25.888696 -167.58285)
					(xy 25.888696 -163.46805) (xy 30.511496 -163.46805) (xy 30.511496 -167.58285) (xy 31.857696 -167.58285)
				)
			)
		)
		(zone
			(layer "F.Cu")
			(hatch none 0.5)
			(connect_pads
				(clearance 0)
			)
			(min_thickness 0.25)
			(keepout
				(tracks allowed)
				(vias not_allowed)
				(pads allowed)
				(copperpour not_allowed)
				(footprints allowed)
			)
			(placement
				(enabled no)
				(sheetname "")
			)
			(fill
				(thermal_gap 0.5)
				(thermal_bridge_width 0.5)
				(island_removal_mode 0)
			)
			(polygon
				(pts
					(xy 31.857696 -127.17145) (xy 24.783796 -127.17145) (xy 24.783796 -120.23725) (xy 25.888696 -120.23725)
					(xy 25.888696 -124.35205) (xy 30.511496 -124.35205) (xy 30.511496 -120.23725) (xy 31.857696 -120.23725)
				)
			)
		)
		(zone
			(layer "F.Cu")
			(hatch none 0.5)
			(connect_pads
				(clearance 0)
			)
			(min_thickness 0.25)
			(keepout
				(tracks not_allowed)
				(vias allowed)
				(pads allowed)
				(copperpour not_allowed)
				(footprints allowed)
			)
			(placement
				(enabled no)
				(sheetname "")
			)
			(fill
				(thermal_gap 0.5)
				(thermal_bridge_width 0.5)
				(island_removal_mode 0)
			)
			(polygon
				(pts
					(xy 31.857696 -127.17145) (xy 24.783796 -127.17145) (xy 24.783796 -120.23725) (xy 25.888696 -120.23725)
					(xy 25.888696 -124.35205) (xy 30.511496 -124.35205) (xy 30.511496 -120.23725) (xy 31.857696 -120.23725)
				)
			)
		)
		(zone
			(layers "F.Cu" "B.Cu" "In1.Cu" "In2.Cu" "In3.Cu" "In4.Cu" "In5.Cu" "In6.Cu")
			(hatch none 0.5)
			(connect_pads
				(clearance 0)
			)
			(min_thickness 0.25)
			(keepout
				(tracks not_allowed)
				(vias allowed)
				(pads allowed)
				(copperpour not_allowed)
				(footprints allowed)
			)
			(placement
				(enabled no)
				(sheetname "")
			)
			(fill
				(thermal_gap 0.5)
				(thermal_bridge_width 0.5)
				(island_removal_mode 0)
			)
			(polygon
				(pts
					(arc
						(start 28.974796 -125.035056)
						(mid 27.425396 -125.035056)
						(end 28.974796 -125.035056)
					)
				)
			)
		)
		(zone
			(layers "F.Cu" "B.Cu" "In1.Cu" "In2.Cu" "In3.Cu" "In4.Cu" "In5.Cu" "In6.Cu")
			(hatch none 0.5)
			(connect_pads
				(clearance 0)
			)
			(min_thickness 0.25)
			(keepout
				(tracks not_allowed)
				(vias allowed)
				(pads allowed)
				(copperpour not_allowed)
				(footprints allowed)
			)
			(placement
				(enabled no)
				(sheetname "")
			)
			(fill
				(thermal_gap 0.5)
				(thermal_bridge_width 0.5)
				(island_removal_mode 0)
			)
			(polygon
				(pts
					(arc
						(start 29.177996 -162.785044)
						(mid 27.222196 -162.785044)
						(end 29.177996 -162.785044)
					)
				)
			)
		)
	)
	(footprint ""
		(layer "F.Cu")
		(at 22.325838 -228.930454 -90)
		(property "Reference" "R1107"
			(at 0 0 270)
			(layer "F.SilkS")
			(hide yes)
			(effects
				(font
					(size 1.27 1.27)
				)
			)
		)
		(property "Value" "200KR2F-L-GP"
			(at 0.064008 -3.993896 270)
			(unlocked yes)
			(layer "F.Fab")
			(hide yes)
			(effects
				(font
					(size 1.016 1.016)
					(thickness 0.1524)
				)
			)
		)
		(property "Device Type" "R402H16"
			(at 0.064008 -5.517896 270)
			(unlocked yes)
			(layer "F.Fab")
			(hide yes)
			(effects
				(font
					(size 1.016 1.016)
					(thickness 0.1524)
				)
			)
		)
		(duplicate_pad_numbers_are_jumpers no)
		(fp_line
			(start -0.508 -0.9398)
			(end -0.508 0.9398)
			(stroke
				(width 0.1524)
				(type default)
			)
			(layer "F.SilkS")
		)
		(fp_line
			(start 0.508 -0.9398)
			(end -0.508 -0.9398)
			(stroke
				(width 0.1524)
				(type default)
			)
			(layer "F.SilkS")
		)
		(fp_rect
			(start -0.508 0.9398)
			(end 0.508 -0.9398)
			(stroke
				(width 0)
				(type default)
			)
			(fill no)
			(layer "F.CrtYd")
		)
		(fp_rect
			(start -0.508 0.9398)
			(end 0.508 -0.9398)
			(stroke
				(width 0)
				(type default)
			)
			(fill no)
			(layer "F.Fab")
		)
		(pad "1" smd custom
			(at 0 -0.4445 270)
			(size 0.1397 0.1397)
			(layers "F.Cu" "F.Mask" "F.Paste")
			(net "P5V_B_1_MODE")
			(options
				(clearance outline)
				(anchor circle)
			)
			(primitives
				(gr_poly
					(pts
						(arc
							(start -0.1778 -0.2794)
							(mid -0.249642 -0.249642)
							(end -0.2794 -0.1778)
						)
						(arc
							(start -0.2794 0.1778)
							(mid -0.249642 0.249642)
							(end -0.1778 0.2794)
						)
						(arc
							(start 0.1778 0.2794)
							(mid 0.249642 0.249642)
							(end 0.2794 0.1778)
						)
						(arc
							(start 0.2794 -0.1778)
							(mid 0.249642 -0.249642)
							(end 0.1778 -0.2794)
						)
					)
					(width 0)
					(fill yes)
				)
			)
		)
		(pad "2" smd custom
			(at 0 0.4445 270)
			(size 0.1397 0.1397)
			(layers "F.Cu" "F.Mask" "F.Paste")
			(net "P5V_B_1_PGOOD")
			(options
				(clearance outline)
				(anchor circle)
			)
			(primitives
				(gr_poly
					(pts
						(arc
							(start -0.1778 -0.2794)
							(mid -0.249642 -0.249642)
							(end -0.2794 -0.1778)
						)
						(arc
							(start -0.2794 0.1778)
							(mid -0.249642 0.249642)
							(end -0.1778 0.2794)
						)
						(arc
							(start 0.1778 0.2794)
							(mid 0.249642 0.249642)
							(end 0.2794 0.1778)
						)
						(arc
							(start 0.2794 -0.1778)
							(mid 0.249642 -0.249642)
							(end 0.1778 -0.2794)
						)
					)
					(width 0)
					(fill yes)
				)
			)
		)
	)
	(footprint ""
		(layer "F.Cu")
		(at 46.863 -248.158 180)
		(property "Reference" "R186"
			(at 0 0 180)
			(layer "F.SilkS")
			(hide yes)
			(effects
				(font
					(size 1.27 1.27)
				)
			)
		)
		(property "Value" "200KR2F-L-GP"
			(at 0.064008 -3.993896 180)
			(unlocked yes)
			(layer "F.Fab")
			(hide yes)
			(effects
				(font
					(size 1.016 1.016)
					(thickness 0.1524)
				)
			)
		)
		(property "Device Type" "R402H16"
			(at 0.064008 -5.517896 180)
			(unlocked yes)
			(layer "F.Fab")
			(hide yes)
			(effects
				(font
					(size 1.016 1.016)
					(thickness 0.1524)
				)
			)
		)
		(duplicate_pad_numbers_are_jumpers no)
		(fp_line
			(start 0.508 -0.9398)
			(end -0.508 -0.9398)
			(stroke
				(width 0.1524)
				(type default)
			)
			(layer "F.SilkS")
		)
		(fp_line
			(start -0.508 -0.9398)
			(end -0.508 0.9398)
			(stroke
				(width 0.1524)
				(type default)
			)
			(layer "F.SilkS")
		)
		(fp_rect
			(start -0.508 0.9398)
			(end 0.508 -0.9398)
			(stroke
				(width 0)
				(type default)
			)
			(fill no)
			(layer "F.CrtYd")
		)
		(fp_rect
			(start -0.508 0.9398)
			(end 0.508 -0.9398)
			(stroke
				(width 0)
				(type default)
			)
			(fill no)
			(layer "F.Fab")
		)
		(pad "1" smd custom
			(at 0 -0.4445 180)
			(size 0.1397 0.1397)
			(layers "F.Cu" "F.Mask" "F.Paste")
			(net "SW_HDD_R1")
			(options
				(clearance outline)
				(anchor circle)
			)
			(primitives
				(gr_poly
					(pts
						(arc
							(start -0.1778 -0.2794)
							(mid -0.249642 -0.249642)
							(end -0.2794 -0.1778)
						)
						(arc
							(start -0.2794 0.1778)
							(mid -0.249642 0.249642)
							(end -0.1778 0.2794)
						)
						(arc
							(start 0.1778 0.2794)
							(mid 0.249642 0.249642)
							(end 0.2794 0.1778)
						)
						(arc
							(start 0.2794 -0.1778)
							(mid 0.249642 -0.249642)
							(end 0.1778 -0.2794)
						)
					)
					(width 0)
					(fill yes)
				)
			)
		)
		(pad "2" smd custom
			(at 0 0.4445 180)
			(size 0.1397 0.1397)
			(layers "F.Cu" "F.Mask" "F.Paste")
			(net "SW_HDD_N1")
			(options
				(clearance outline)
				(anchor circle)
			)
			(primitives
				(gr_poly
					(pts
						(arc
							(start -0.1778 -0.2794)
							(mid -0.249642 -0.249642)
							(end -0.2794 -0.1778)
						)
						(arc
							(start -0.2794 0.1778)
							(mid -0.249642 0.249642)
							(end -0.1778 0.2794)
						)
						(arc
							(start 0.1778 0.2794)
							(mid 0.249642 0.249642)
							(end 0.2794 0.1778)
						)
						(arc
							(start 0.2794 -0.1778)
							(mid 0.249642 -0.249642)
							(end 0.1778 -0.2794)
						)
					)
					(width 0)
					(fill yes)
				)
			)
		)
	)
)
